# BASEBOARD_FAB2 (Tioga Pass) — schematic netlist excerpt (pin names and nets, part order shuffled) for the footprints in the layout excerpt that follows; sources: Cadence DE-HDL packaged netlist, KiCad conversion of Wiwynn_Tioga_Pass_MB.brd

C7W7  SC22U16V5MX-4-GP  20%  pkg SMD-BCG5  page 220 : \1\ = VR_FET_SW_P12V_STBY_PVDDQ_DEF ; \2\ = GND

CR25W2  DIODEAC_DUAL_ARRAY  ESD3V3U4ULC IC  pkg SM9  page 252
  AC0  = V_IBMC_5V_DDC_SDA_J
  AC1  = V_IBMC_5V_DDC_SCL_J
  GND(0)  = GND
  AC2  = V_IO_VSYNC_J
  AC3  = V_IO_HSYNC_J
  OUT3  = V_IO_HSYNC_J
  OUT2  = V_IO_VSYNC_J
  OUT1  = V_IBMC_5V_DDC_SCL_J
  OUT0  = V_IBMC_5V_DDC_SDA_J

R2T18  RES  49.9 1% CHIP  pkg 0402  page 156 : A = RST_BMC_SYSRST_BTN_OUT_B_R_N ; B = RST_BMC_SYSRST_BTN_OUT_B_N

(kicad_pcb
	(version 20260206)
	(generator "pcbnew")
	(generator_version "10.0")
	(general
		(thickness 1.6)
		(legacy_teardrops no)
	)
	(paper "A4")
	(title_block
		(title "Wiwynn_Tioga_Pass_MB.brd")
		(comment 1 "Tioga Pass / footprints 3606-3608 of 4770")
	)
	(layers
		(0 "F.Cu" signal "TOP")
		(4 "In1.Cu" signal "L2GND")
		(6 "In2.Cu" signal "L3")
		(8 "In3.Cu" signal "L4GND")
		(10 "In4.Cu" signal "L5")
		(12 "In5.Cu" signal "L6GND")
		(14 "In6.Cu" signal "L7VCC")
		(16 "In7.Cu" signal "L8VCC")
		(18 "In8.Cu" signal "L9GND")
		(20 "In9.Cu" signal "L10")
		(22 "In10.Cu" signal "L11GND")
		(24 "In11.Cu" signal "L12")
		(26 "In12.Cu" signal "L13GND")
		(2 "B.Cu" signal "BOTTOM")
		(9 "F.Adhes" user "F.Adhesive")
		(11 "B.Adhes" user "B.Adhesive")
		(13 "F.Paste" user "Package Geometry/Pastemask Top")
		(15 "B.Paste" user "Package Geometry/Pastemask Bottom")
		(5 "F.SilkS" user "Ref Des/Silkscreen Top")
		(7 "B.SilkS" user "Ref Des/Silkscreen Bottom")
		(1 "F.Mask" user "Board Geometry/Soldermask Top")
		(3 "B.Mask" user "Board Geometry/Soldermask Bottom")
		(17 "Dwgs.User" user "User.Drawings")
		(19 "Cmts.User" user "User.Comments")
		(21 "Eco1.User" user "User.Eco1")
		(23 "Eco2.User" user "User.Eco2")
		(25 "Edge.Cuts" user "Board Geometry/Outline")
		(27 "Margin" user)
		(31 "F.CrtYd" user "Package Geometry/Place Bound Top")
		(29 "B.CrtYd" user "Package Geometry/Place Bound Bottom")
		(35 "F.Fab" user "Ref Des/Assembly Top")
		(33 "B.Fab" user "Ref Des/Assembly Bottom")
	)
	(footprint ""
		(layer "B.Cu")
		(at 498.487954 -47.771812)
		(property "Reference" "CR25W2"
			(at 1.495806 -1.067816 0)
			(unlocked yes)
			(layer "B.SilkS")
			(effects
				(font
					(size 0.4064 0.254)
					(thickness 0.1524)
				)
				(justify left mirror)
			)
		)
		(property "Value" ""
			(at 0 0 0)
			(layer "B.Fab")
			(effects
				(font
					(size 1.27 1.27)
				)
				(justify mirror)
			)
		)
		(duplicate_pad_numbers_are_jumpers no)
		(fp_circle
			(center 0.589026 -0.5334)
			(end 0.716026 -0.5334)
			(stroke
				(width 0.254)
				(type default)
			)
			(fill no)
			(layer "B.SilkS")
		)
		(fp_rect
			(start 0.225552 2.167382)
			(end -0.809498 -0.167386)
			(stroke
				(width 0)
				(type default)
			)
			(fill no)
			(layer "B.CrtYd")
		)
		(fp_line
			(start -0.809498 -0.167386)
			(end -0.809498 2.167382)
			(stroke
				(width 0.1)
				(type default)
			)
			(layer "B.Fab")
		)
		(fp_line
			(start -0.809498 2.167382)
			(end 0.225552 2.167382)
			(stroke
				(width 0.1)
				(type default)
			)
			(layer "B.Fab")
		)
		(fp_line
			(start 0.225552 -0.167386)
			(end -0.809498 -0.167386)
			(stroke
				(width 0.1)
				(type default)
			)
			(layer "B.Fab")
		)
		(fp_line
			(start 0.225552 2.167382)
			(end 0.225552 -0.167386)
			(stroke
				(width 0.1)
				(type default)
			)
			(layer "B.Fab")
		)
		(fp_circle
			(center 0.589026 -0.5334)
			(end 0.716026 -0.5334)
			(stroke
				(width 0.254)
				(type default)
			)
			(fill no)
			(layer "B.Fab")
		)
		(pad "1" smd rect
			(at 0 0 180)
			(size 0.3556 0.2032)
			(layers "B.Cu" "B.Mask" "B.Paste")
			(net "V_IBMC_5V_DDC_SDA_J")
		)
		(pad "2" smd rect
			(at 0 0.500126 180)
			(size 0.3556 0.2032)
			(layers "B.Cu" "B.Mask" "B.Paste")
			(net "V_IBMC_5V_DDC_SCL_J")
		)
		(pad "3" smd rect
			(at -0.2921 0.999998 180)
			(size 0.9398 0.4064)
			(layers "B.Cu" "B.Mask" "B.Paste")
			(net "GND")
		)
		(pad "4" smd rect
			(at 0 1.500124 180)
			(size 0.3556 0.2032)
			(layers "B.Cu" "B.Mask" "B.Paste")
			(net "V_IO_VSYNC_J")
		)
		(pad "5" smd rect
			(at 0 1.999996 180)
			(size 0.3556 0.2032)
			(layers "B.Cu" "B.Mask" "B.Paste")
			(net "V_IO_HSYNC_J")
		)
		(pad "6" smd rect
			(at -0.583946 1.999996 180)
			(size 0.3556 0.2032)
			(layers "B.Cu" "B.Mask" "B.Paste")
			(net "V_IO_HSYNC_J")
		)
		(pad "7" smd rect
			(at -0.583946 1.500124 180)
			(size 0.3556 0.2032)
			(layers "B.Cu" "B.Mask" "B.Paste")
			(net "V_IO_VSYNC_J")
		)
		(pad "8" smd rect
			(at -0.583946 0.500126 180)
			(size 0.3556 0.2032)
			(layers "B.Cu" "B.Mask" "B.Paste")
			(net "V_IBMC_5V_DDC_SCL_J")
		)
		(pad "9" smd rect
			(at -0.583946 0 180)
			(size 0.3556 0.2032)
			(layers "B.Cu" "B.Mask" "B.Paste")
			(net "V_IBMC_5V_DDC_SDA_J")
		)
	)
	(footprint ""
		(layer "B.Cu")
		(at 363.032294 -145.471642)
		(property "Reference" "C7W7"
			(at 0 0 0)
			(layer "B.SilkS")
			(hide yes)
			(effects
				(font
					(size 1.27 1.27)
				)
				(justify mirror)
			)
		)
		(property "Value" "*"
			(at 0.0762 -6.2357 0)
			(unlocked yes)
			(layer "B.Fab")
			(hide yes)
			(effects
				(font
					(size 1.27 1.016)
					(thickness 0.1524)
				)
				(justify mirror)
			)
		)
		(property "Device Type" "SC22U16V5MX-4-GP_SMD-BCG5-SC22A"
			(at 0.0762 -8.2677 0)
			(unlocked yes)
			(layer "B.Fab")
			(hide yes)
			(effects
				(font
					(size 1.27 1.016)
					(thickness 0.1524)
				)
				(justify mirror)
			)
		)
		(duplicate_pad_numbers_are_jumpers no)
		(fp_line
			(start -0.635 0)
			(end 0.635 0)
			(stroke
				(width 0.508)
				(type default)
			)
			(layer "B.SilkS")
		)
		(fp_rect
			(start 0.9652 1.778)
			(end -0.9652 -1.778)
			(stroke
				(width 0)
				(type default)
			)
			(fill no)
			(layer "B.CrtYd")
		)
		(fp_poly
			(pts
				(xy 0.9652 -1.778) (xy -0.9652 -1.778) (xy -0.9652 1.778) (xy 0.9652 1.778)
			)
			(stroke
				(width 0)
				(type default)
			)
			(fill no)
			(layer "B.Fab")
		)
		(pad "1" smd rect
			(at 0 -0.9652 180)
			(size 1.397 1.143)
			(layers "B.Cu" "B.Mask" "B.Paste")
			(net "VR_FET_SW_P12V_STBY_PVDDQ_DEF")
		)
		(pad "2" smd rect
			(at 0 0.9652 180)
			(size 1.397 1.143)
			(layers "B.Cu" "B.Mask" "B.Paste")
			(net "GND")
		)
	)
	(footprint ""
		(layer "B.Cu")
		(at 393.0396 -37.1348 180)
		(property "Reference" "R2T18"
			(at 0 0 0)
			(layer "B.SilkS")
			(hide yes)
			(effects
				(font
					(size 1.27 1.27)
				)
				(justify mirror)
			)
		)
		(property "Value" ""
			(at 0 0 0)
			(layer "B.Fab")
			(effects
				(font
					(size 1.27 1.27)
				)
				(justify mirror)
			)
		)
		(duplicate_pad_numbers_are_jumpers no)
		(fp_poly
			(pts
				(xy 0.2794 -0.1016) (xy -0.2794 -0.1016) (xy -0.2794 0.9906) (xy 0.2794 0.9906)
			)
			(stroke
				(width 0)
				(type default)
			)
			(fill no)
			(layer "B.CrtYd")
		)
		(fp_line
			(start 0.2794 0.9906)
			(end -0.2794 0.9906)
			(stroke
				(width 0.1)
				(type default)
			)
			(layer "B.Fab")
		)
		(fp_line
			(start 0.2794 -0.1016)
			(end 0.2794 0.9906)
			(stroke
				(width 0.1)
				(type default)
			)
			(layer "B.Fab")
		)
		(fp_line
			(start -0.2794 0.9906)
			(end -0.2794 -0.1016)
			(stroke
				(width 0.1)
				(type default)
			)
			(layer "B.Fab")
		)
		(fp_line
			(start -0.2794 -0.1016)
			(end 0.2794 -0.1016)
			(stroke
				(width 0.1)
				(type default)
			)
			(layer "B.Fab")
		)
		(pad "1" smd rect
			(at 0 0)
			(size 0.508 0.508)
			(layers "B.Cu" "B.Mask" "B.Paste")
			(net "RST_BMC_SYSRST_BTN_OUT_B_R_N")
		)
		(pad "2" smd rect
			(at 0 0.889)
			(size 0.508 0.508)
			(layers "B.Cu" "B.Mask" "B.Paste")
			(net "RST_BMC_SYSRST_BTN_OUT_B_N")
		)
		(zone
			(layer "B.Cu")
			(hatch none 0.5)
			(connect_pads
				(clearance 0)
			)
			(min_thickness 0.25)
			(keepout
				(tracks not_allowed)
				(vias allowed)
				(pads allowed)
				(copperpour not_allowed)
				(footprints allowed)
			)
			(placement
				(enabled no)
				(sheetname "")
			)
			(fill
				(thermal_gap 0.5)
				(thermal_bridge_width 0.5)
				(island_removal_mode 0)
			)
			(polygon
				(pts
					(xy 392.7856 -37.7698) (xy 393.2936 -37.7698) (xy 393.2936 -37.3888) (xy 392.7856 -37.3888)
				)
			)
		)
		(zone
			(layer "B.Cu")
			(hatch none 0.5)
			(connect_pads
				(clearance 0)
			)
			(min_thickness 0.25)
			(keepout
				(tracks allowed)
				(vias not_allowed)
				(pads allowed)
				(copperpour not_allowed)
				(footprints allowed)
			)
			(placement
				(enabled no)
				(sheetname "")
			)
			(fill
				(thermal_gap 0.5)
				(thermal_bridge_width 0.5)
				(island_removal_mode 0)
			)
			(polygon
				(pts
					(xy 392.7856 -37.3888) (xy 393.2936 -37.3888) (xy 393.2936 -37.7698) (xy 392.7856 -37.7698)
				)
			)
		)
	)
)
